# BASEBOARD_FAB2 (Tioga Pass) — schematic netlist excerpt (pin names and nets, part order shuffled) for the footprints in the layout excerpt that follows; sources: Cadence DE-HDL packaged netlist, KiCad conversion of Wiwynn_Tioga_Pass_MB.brd

CR3U1  DIODE  1N5819HW IC  pkg SMLF  page 189 : C = P3V3_STBY_PLD_D ; A = P3V3_STBY
C2L9  CAP_A  0.01UF 25V 10% X7R  pkg 0402V  page 173 : A = SATA6G_PCH_PCIE_UP_SATA_RXN<5> ; B = SATA6G_P5_RX_C_DN
R8D30  RES  10.0K 1% CHIP  pkg 0402  page 89 : A = IRQ_DIMM_SAVE_N ; B = IRQ_DIMM_SAVE_R_N

(kicad_pcb
	(version 20260206)
	(generator "pcbnew")
	(generator_version "10.0")
	(general
		(thickness 1.6)
		(legacy_teardrops no)
	)
	(paper "A4")
	(title_block
		(title "Wiwynn_Tioga_Pass_MB.brd")
		(comment 1 "Tioga Pass / footprints 2943-2945 of 4770")
	)
	(layers
		(0 "F.Cu" signal "TOP")
		(4 "In1.Cu" signal "L2GND")
		(6 "In2.Cu" signal "L3")
		(8 "In3.Cu" signal "L4GND")
		(10 "In4.Cu" signal "L5")
		(12 "In5.Cu" signal "L6GND")
		(14 "In6.Cu" signal "L7VCC")
		(16 "In7.Cu" signal "L8VCC")
		(18 "In8.Cu" signal "L9GND")
		(20 "In9.Cu" signal "L10")
		(22 "In10.Cu" signal "L11GND")
		(24 "In11.Cu" signal "L12")
		(26 "In12.Cu" signal "L13GND")
		(2 "B.Cu" signal "BOTTOM")
		(9 "F.Adhes" user "F.Adhesive")
		(11 "B.Adhes" user "B.Adhesive")
		(13 "F.Paste" user "Package Geometry/Pastemask Top")
		(15 "B.Paste" user "Package Geometry/Pastemask Bottom")
		(5 "F.SilkS" user "Ref Des/Silkscreen Top")
		(7 "B.SilkS" user "Ref Des/Silkscreen Bottom")
		(1 "F.Mask" user "Board Geometry/Soldermask Top")
		(3 "B.Mask" user "Board Geometry/Soldermask Bottom")
		(17 "Dwgs.User" user "User.Drawings")
		(19 "Cmts.User" user "User.Comments")
		(21 "Eco1.User" user "User.Eco1")
		(23 "Eco2.User" user "User.Eco2")
		(25 "Edge.Cuts" user "Board Geometry/Outline")
		(27 "Margin" user)
		(31 "F.CrtYd" user "Package Geometry/Place Bound Top")
		(29 "B.CrtYd" user "Package Geometry/Place Bound Bottom")
		(35 "F.Fab" user "Ref Des/Assembly Top")
		(33 "B.Fab" user "Ref Des/Assembly Bottom")
	)
	(footprint ""
		(layer "B.Cu")
		(at 378.5362 -5.7658 -90)
		(property "Reference" "CR3U1"
			(at -1.6764 0.1524 0)
			(unlocked yes)
			(layer "B.SilkS")
			(effects
				(font
					(size 0.4064 0.254)
					(thickness 0.1524)
				)
				(justify left mirror)
			)
		)
		(property "Value" ""
			(at 0 0 90)
			(layer "B.Fab")
			(effects
				(font
					(size 1.27 1.27)
				)
				(justify mirror)
			)
		)
		(duplicate_pad_numbers_are_jumpers no)
		(fp_line
			(start -0.9144 2.9464)
			(end -0.8382 2.9464)
			(stroke
				(width 0.1524)
				(type default)
			)
			(layer "B.SilkS")
		)
		(fp_line
			(start 0.9144 2.9464)
			(end 0.8382 2.9464)
			(stroke
				(width 0.1524)
				(type default)
			)
			(layer "B.SilkS")
		)
		(fp_line
			(start -0.9144 0.1016)
			(end -0.9144 2.9464)
			(stroke
				(width 0.1524)
				(type default)
			)
			(layer "B.SilkS")
		)
		(fp_line
			(start -0.8382 0.1016)
			(end -0.9144 0.1016)
			(stroke
				(width 0.1524)
				(type default)
			)
			(layer "B.SilkS")
		)
		(fp_line
			(start 0.8382 0.1016)
			(end 0.9144 0.1016)
			(stroke
				(width 0.1524)
				(type default)
			)
			(layer "B.SilkS")
		)
		(fp_line
			(start 0.9144 0.1016)
			(end 0.9144 2.9464)
			(stroke
				(width 0.1524)
				(type default)
			)
			(layer "B.SilkS")
		)
		(fp_circle
			(center -1.128776 -0.907288)
			(end -1.128776 -1.034288)
			(stroke
				(width 0.254)
				(type default)
			)
			(fill no)
			(layer "B.SilkS")
		)
		(fp_poly
			(pts
				(xy 0 0.1016) (xy -0.5334 0.1016) (xy -0.7366 0.1016) (xy -0.9144 0.1016) (xy -0.9144 2.9464) (xy -0.8382 2.9464)
				(xy -0.762 2.9464) (xy 0.9144 2.9464) (xy 0.9144 2.7686) (xy 0.9144 2.159) (xy 0.9144 0.1016) (xy 0.7366 0.1016)
				(xy 0.5842 0.1016)
			)
			(stroke
				(width 0)
				(type default)
			)
			(fill no)
			(layer "B.CrtYd")
		)
		(fp_line
			(start -0.9144 2.9464)
			(end -0.9144 0.1016)
			(stroke
				(width 0.1)
				(type default)
			)
			(layer "B.Fab")
		)
		(fp_line
			(start 0.9144 2.9464)
			(end -0.9144 2.9464)
			(stroke
				(width 0.1)
				(type default)
			)
			(layer "B.Fab")
		)
		(fp_line
			(start -0.9144 0.1016)
			(end 0.9144 0.1016)
			(stroke
				(width 0.1)
				(type default)
			)
			(layer "B.Fab")
		)
		(fp_line
			(start 0.9144 0.1016)
			(end 0.9144 2.9464)
			(stroke
				(width 0.1)
				(type default)
			)
			(layer "B.Fab")
		)
		(fp_circle
			(center -1.128776 -0.907288)
			(end -1.128776 -1.034288)
			(stroke
				(width 0.254)
				(type default)
			)
			(fill no)
			(layer "B.Fab")
		)
		(pad "1" smd rect
			(at 0 0 180)
			(size 1.524 0.762)
			(layers "B.Cu" "B.Mask" "B.Paste")
			(net "P3V3_STBY_PLD_D")
		)
		(pad "2" smd rect
			(at 0 3.048)
			(size 1.524 0.762)
			(layers "B.Cu" "B.Mask" "B.Paste")
			(net "P3V3_STBY")
		)
	)
	(footprint ""
		(layer "B.Cu")
		(at 410.464 -153.162 90)
		(property "Reference" "C2L9"
			(at 0 0 90)
			(layer "B.SilkS")
			(hide yes)
			(effects
				(font
					(size 1.27 1.27)
				)
				(justify mirror)
			)
		)
		(property "Value" ""
			(at 0 0 90)
			(layer "B.Fab")
			(effects
				(font
					(size 1.27 1.27)
				)
				(justify mirror)
			)
		)
		(duplicate_pad_numbers_are_jumpers no)
		(fp_poly
			(pts
				(xy -0.3048 -0.1016) (xy -0.3048 0.9906) (xy 0.3048 0.9906) (xy 0.3048 -0.1016)
			)
			(stroke
				(width 0)
				(type default)
			)
			(fill no)
			(layer "B.CrtYd")
		)
		(fp_line
			(start 0.3048 -0.1016)
			(end 0.3048 0.9906)
			(stroke
				(width 0.1)
				(type default)
			)
			(layer "B.Fab")
		)
		(fp_line
			(start -0.3048 -0.1016)
			(end 0.3048 -0.1016)
			(stroke
				(width 0.1)
				(type default)
			)
			(layer "B.Fab")
		)
		(fp_line
			(start 0.3048 0.9906)
			(end -0.3048 0.9906)
			(stroke
				(width 0.1)
				(type default)
			)
			(layer "B.Fab")
		)
		(fp_line
			(start -0.3048 0.9906)
			(end -0.3048 -0.1016)
			(stroke
				(width 0.1)
				(type default)
			)
			(layer "B.Fab")
		)
		(pad "1" smd rect
			(at 0 0 270)
			(size 0.508 0.508)
			(layers "B.Cu" "B.Mask" "B.Paste")
			(net "SATA6G_PCH_PCIE_UP_SATA_RXN<5>")
		)
		(pad "2" smd rect
			(at 0 0.889 270)
			(size 0.508 0.508)
			(layers "B.Cu" "B.Mask" "B.Paste")
			(net "SATA6G_P5_RX_C_DN")
		)
		(zone
			(layer "B.Cu")
			(hatch none 0.5)
			(connect_pads
				(clearance 0)
			)
			(min_thickness 0.25)
			(keepout
				(tracks allowed)
				(vias not_allowed)
				(pads allowed)
				(copperpour not_allowed)
				(footprints allowed)
			)
			(placement
				(enabled no)
				(sheetname "")
			)
			(fill
				(thermal_gap 0.5)
				(thermal_bridge_width 0.5)
				(island_removal_mode 0)
			)
			(polygon
				(pts
					(xy 410.718 -153.416) (xy 410.718 -152.908) (xy 411.099 -152.908) (xy 411.099 -153.416)
				)
			)
		)
		(zone
			(layer "B.Cu")
			(hatch none 0.5)
			(connect_pads
				(clearance 0)
			)
			(min_thickness 0.25)
			(keepout
				(tracks not_allowed)
				(vias allowed)
				(pads allowed)
				(copperpour not_allowed)
				(footprints allowed)
			)
			(placement
				(enabled no)
				(sheetname "")
			)
			(fill
				(thermal_gap 0.5)
				(thermal_bridge_width 0.5)
				(island_removal_mode 0)
			)
			(polygon
				(pts
					(xy 411.099 -153.416) (xy 411.099 -152.908) (xy 410.718 -152.908) (xy 410.718 -153.416)
				)
			)
		)
	)
	(footprint ""
		(layer "B.Cu")
		(at 312.786268 -31.69285)
		(property "Reference" "R8D30"
			(at 0 0 0)
			(layer "B.SilkS")
			(hide yes)
			(effects
				(font
					(size 1.27 1.27)
				)
				(justify mirror)
			)
		)
		(property "Value" ""
			(at 0 0 0)
			(layer "B.Fab")
			(effects
				(font
					(size 1.27 1.27)
				)
				(justify mirror)
			)
		)
		(duplicate_pad_numbers_are_jumpers no)
		(fp_poly
			(pts
				(xy 0.2794 -0.1016) (xy -0.2794 -0.1016) (xy -0.2794 0.9906) (xy 0.2794 0.9906)
			)
			(stroke
				(width 0)
				(type default)
			)
			(fill no)
			(layer "B.CrtYd")
		)
		(fp_line
			(start -0.2794 -0.1016)
			(end 0.2794 -0.1016)
			(stroke
				(width 0.1)
				(type default)
			)
			(layer "B.Fab")
		)
		(fp_line
			(start -0.2794 0.9906)
			(end -0.2794 -0.1016)
			(stroke
				(width 0.1)
				(type default)
			)
			(layer "B.Fab")
		)
		(fp_line
			(start 0.2794 -0.1016)
			(end 0.2794 0.9906)
			(stroke
				(width 0.1)
				(type default)
			)
			(layer "B.Fab")
		)
		(fp_line
			(start 0.2794 0.9906)
			(end -0.2794 0.9906)
			(stroke
				(width 0.1)
				(type default)
			)
			(layer "B.Fab")
		)
		(pad "1" smd rect
			(at 0 0 180)
			(size 0.508 0.508)
			(layers "B.Cu" "B.Mask" "B.Paste")
			(net "IRQ_DIMM_SAVE_N")
		)
		(pad "2" smd rect
			(at 0 0.889 180)
			(size 0.508 0.508)
			(layers "B.Cu" "B.Mask" "B.Paste")
			(net "IRQ_DIMM_SAVE_R_N")
		)
		(zone
			(layer "B.Cu")
			(hatch none 0.5)
			(connect_pads
				(clearance 0)
			)
			(min_thickness 0.25)
			(keepout
				(tracks allowed)
				(vias not_allowed)
				(pads allowed)
				(copperpour not_allowed)
				(footprints allowed)
			)
			(placement
				(enabled no)
				(sheetname "")
			)
			(fill
				(thermal_gap 0.5)
				(thermal_bridge_width 0.5)
				(island_removal_mode 0)
			)
			(polygon
				(pts
					(xy 313.040268 -31.43885) (xy 312.532268 -31.43885) (xy 312.532268 -31.05785) (xy 313.040268 -31.05785)
				)
			)
		)
		(zone
			(layer "B.Cu")
			(hatch none 0.5)
			(connect_pads
				(clearance 0)
			)
			(min_thickness 0.25)
			(keepout
				(tracks not_allowed)
				(vias allowed)
				(pads allowed)
				(copperpour not_allowed)
				(footprints allowed)
			)
			(placement
				(enabled no)
				(sheetname "")
			)
			(fill
				(thermal_gap 0.5)
				(thermal_bridge_width 0.5)
				(island_removal_mode 0)
			)
			(polygon
				(pts
					(xy 313.040268 -31.05785) (xy 312.532268 -31.05785) (xy 312.532268 -31.43885) (xy 313.040268 -31.43885)
				)
			)
		)
	)
)
